(kicad_pcb
	(version 20260206)
	(generator "pcbnew")
	(generator_version "10.0")
	(general
		(thickness 1.6)
		(legacy_teardrops no)
	)
	(paper "A4")
	(title_block
		(title "Bryce Canyon_F.DPB_16315-1-OCP.brd")
		(comment 1 "Bryce Canyon / footprint 944 of 2223 (PCIE1), pads 1-73 of 76")
	)
	(layers
		(0 "F.Cu" signal "TOP")
		(4 "In1.Cu" signal "L2GND")
		(6 "In2.Cu" signal "L3")
		(8 "In3.Cu" signal "L4GND")
		(10 "In4.Cu" signal "L5")
		(12 "In5.Cu" signal "L6VCC")
		(14 "In6.Cu" signal "L7VCC")
		(16 "In7.Cu" signal "L8")
		(18 "In8.Cu" signal "L9GND")
		(20 "In9.Cu" signal "L10")
		(22 "In10.Cu" signal "L11GND")
		(2 "B.Cu" signal "BOTTOM")
		(9 "F.Adhes" user "F.Adhesive")
		(11 "B.Adhes" user "B.Adhesive")
		(13 "F.Paste" user "Package Geometry/Pastemask Top")
		(15 "B.Paste" user "Package Geometry/Pastemask Bottom")
		(5 "F.SilkS" user "Ref Des/Silkscreen Top")
		(7 "B.SilkS" user "Ref Des/Silkscreen Bottom")
		(1 "F.Mask" user "Board Geometry/Soldermask Top")
		(3 "B.Mask" user "Board Geometry/Soldermask Bottom")
		(17 "Dwgs.User" user "User.Drawings")
		(19 "Cmts.User" user "User.Comments")
		(21 "Eco1.User" user "User.Eco1")
		(23 "Eco2.User" user "User.Eco2")
		(25 "Edge.Cuts" user "Board Geometry/Outline")
		(27 "Margin" user)
		(31 "F.CrtYd" user "Package Geometry/Place Bound Top")
		(29 "B.CrtYd" user "Package Geometry/Place Bound Bottom")
		(35 "F.Fab" user "Ref Des/Assembly Top")
		(33 "B.Fab" user "Ref Des/Assembly Bottom")
	)
	(footprint ""
		(layer "F.Cu")
		(at 287.83661 -263.702292 -90)
		(property "Reference" "PCIE1"
			(at 0 0 270)
			(layer "F.SilkS")
			(hide yes)
			(effects
				(font
					(size 1.27 1.27)
				)
			)
		)
		(property "Value" "AMP-CONN76-8R-5-GP"
			(at -8.9408 -15.1892 270)
			(unlocked yes)
			(layer "F.Fab")
			(hide yes)
			(effects
				(font
					(size 1.016 1.016)
					(thickness 0.1524)
				)
			)
		)
		(property "Device Type" "PREFIT-76P-165151H483"
			(at -8.9408 -16.7132 270)
			(unlocked yes)
			(layer "F.Fab")
			(hide yes)
			(effects
				(font
					(size 1.016 1.016)
					(thickness 0.1524)
				)
			)
		)
		(duplicate_pad_numbers_are_jumpers no)
		(pad "A1" thru_hole circle
			(at 0 0 270)
			(size 0.762 0.762)
			(drill 0.359918)
			(layers "*.Cu" "*.Mask")
			(remove_unused_layers no)
			(net "PCIE_COMP_A_TO_SCC_A_0_DP")
			(clearance 0.1651)
			(thermal_gap 0.1651)
		)
		(pad "A2" thru_hole circle
			(at 1.800098 0.999998 270)
			(size 0.762 0.762)
			(drill 0.359918)
			(layers "*.Cu" "*.Mask")
			(remove_unused_layers no)
			(net "PCIE_COMP_A_TO_SCC_A_1_DP")
			(clearance 0.1651)
			(thermal_gap 0.1651)
		)
		(pad "A3" thru_hole circle
			(at 3.599942 0 270)
			(size 0.762 0.762)
			(drill 0.359918)
			(layers "*.Cu" "*.Mask")
			(remove_unused_layers no)
			(net "PCIE_COMP_A_TO_SCC_A_2_DP")
			(clearance 0.1651)
			(thermal_gap 0.1651)
		)
		(pad "A4" thru_hole circle
			(at 5.40004 0.999998 270)
			(size 0.762 0.762)
			(drill 0.359918)
			(layers "*.Cu" "*.Mask")
			(remove_unused_layers no)
			(net "PCIE_COMP_A_TO_SCC_A_3_DP")
			(clearance 0.1651)
			(thermal_gap 0.1651)
		)
		(pad "A5" thru_hole circle
			(at 7.199884 0 270)
			(size 0.762 0.762)
			(drill 0.359918)
			(layers "*.Cu" "*.Mask")
			(remove_unused_layers no)
			(net "PCIE_COMP_A_TO_SCC_A_4_DP")
			(clearance 0.1651)
			(thermal_gap 0.1651)
		)
		(pad "A6" thru_hole circle
			(at 8.999982 0.999998 270)
			(size 0.762 0.762)
			(drill 0.359918)
			(layers "*.Cu" "*.Mask")
			(remove_unused_layers no)
			(net "PCIE_COMP_A_TO_SCC_A_5_DP")
			(clearance 0.1651)
			(thermal_gap 0.1651)
		)
		(pad "A7" thru_hole circle
			(at 10.80008 0 270)
			(size 0.762 0.762)
			(drill 0.359918)
			(layers "*.Cu" "*.Mask")
			(remove_unused_layers no)
			(net "PCIE_COMP_A_TO_SCC_A_6_DP")
			(clearance 0.1651)
			(thermal_gap 0.1651)
		)
		(pad "A8" thru_hole circle
			(at 12.599924 0.999998 270)
			(size 0.762 0.762)
			(drill 0.359918)
			(layers "*.Cu" "*.Mask")
			(remove_unused_layers no)
			(net "PCIE_COMP_A_TO_SCC_A_7_DP")
			(clearance 0.1651)
			(thermal_gap 0.1651)
		)
		(pad "B1" thru_hole circle
			(at 0 1.400048 270)
			(size 0.762 0.762)
			(drill 0.359918)
			(layers "*.Cu" "*.Mask")
			(remove_unused_layers no)
			(net "PCIE_COMP_A_TO_SCC_A_0_DN")
			(clearance 0.1651)
			(thermal_gap 0.1651)
		)
		(pad "B2" thru_hole circle
			(at 1.800098 2.400046 270)
			(size 0.762 0.762)
			(drill 0.359918)
			(layers "*.Cu" "*.Mask")
			(remove_unused_layers no)
			(net "PCIE_COMP_A_TO_SCC_A_1_DN")
			(clearance 0.1651)
			(thermal_gap 0.1651)
		)
		(pad "B3" thru_hole circle
			(at 3.599942 1.400048 270)
			(size 0.762 0.762)
			(drill 0.359918)
			(layers "*.Cu" "*.Mask")
			(remove_unused_layers no)
			(net "PCIE_COMP_A_TO_SCC_A_2_DN")
			(clearance 0.1651)
			(thermal_gap 0.1651)
		)
		(pad "B4" thru_hole circle
			(at 5.40004 2.400046 270)
			(size 0.762 0.762)
			(drill 0.359918)
			(layers "*.Cu" "*.Mask")
			(remove_unused_layers no)
			(net "PCIE_COMP_A_TO_SCC_A_3_DN")
			(clearance 0.1651)
			(thermal_gap 0.1651)
		)
		(pad "B5" thru_hole circle
			(at 7.199884 1.400048 270)
			(size 0.762 0.762)
			(drill 0.359918)
			(layers "*.Cu" "*.Mask")
			(remove_unused_layers no)
			(net "PCIE_COMP_A_TO_SCC_A_4_DN")
			(clearance 0.1651)
			(thermal_gap 0.1651)
		)
		(pad "B6" thru_hole circle
			(at 8.999982 2.400046 270)
			(size 0.762 0.762)
			(drill 0.359918)
			(layers "*.Cu" "*.Mask")
			(remove_unused_layers no)
			(net "PCIE_COMP_A_TO_SCC_A_5_DN")
			(clearance 0.1651)
			(thermal_gap 0.1651)
		)
		(pad "B7" thru_hole circle
			(at 10.80008 1.400048 270)
			(size 0.762 0.762)
			(drill 0.359918)
			(layers "*.Cu" "*.Mask")
			(remove_unused_layers no)
			(net "PCIE_COMP_A_TO_SCC_A_6_DN")
			(clearance 0.1651)
			(thermal_gap 0.1651)
		)
		(pad "B8" thru_hole circle
			(at 12.599924 2.400046 270)
			(size 0.762 0.762)
			(drill 0.359918)
			(layers "*.Cu" "*.Mask")
			(remove_unused_layers no)
			(net "PCIE_COMP_A_TO_SCC_A_7_DN")
			(clearance 0.1651)
			(thermal_gap 0.1651)
		)
		(pad "C1" thru_hole circle
			(at 0 3.599942 270)
			(size 0.762 0.762)
			(drill 0.359918)
			(layers "*.Cu" "*.Mask")
			(remove_unused_layers no)
			(net "PCIE_COMP_A_TO_SCC_A_CLK_0_DP")
			(clearance 0.1651)
			(thermal_gap 0.1651)
		)
		(pad "C2" thru_hole circle
			(at 1.800098 4.59994 270)
			(size 0.762 0.762)
			(drill 0.359918)
			(layers "*.Cu" "*.Mask")
			(remove_unused_layers no)
			(net "I2C_BMC_B_EXP_A_SCL")
			(clearance 0.1651)
			(thermal_gap 0.1651)
		)
		(pad "C3" thru_hole circle
			(at 3.599942 3.599942 270)
			(size 0.762 0.762)
			(drill 0.359918)
			(layers "*.Cu" "*.Mask")
			(remove_unused_layers no)
			(net "I2C_SCC_A_SCL_BUF")
			(clearance 0.1651)
			(thermal_gap 0.1651)
		)
		(pad "C4" thru_hole circle
			(at 5.40004 4.59994 270)
			(size 0.762 0.762)
			(drill 0.359918)
			(layers "*.Cu" "*.Mask")
			(remove_unused_layers no)
			(net "COMP_A_EXP_A_SPARE_0")
			(clearance 0.1651)
			(thermal_gap 0.1651)
		)
		(pad "C5" thru_hole circle
			(at 7.199884 3.599942 270)
			(size 0.762 0.762)
			(drill 0.359918)
			(layers "*.Cu" "*.Mask")
			(remove_unused_layers no)
			(net "UART_IOC_A_TX")
			(clearance 0.1651)
			(thermal_gap 0.1651)
		)
		(pad "C6" thru_hole circle
			(at 8.999982 4.59994 270)
			(size 0.762 0.762)
			(drill 0.359918)
			(layers "*.Cu" "*.Mask")
			(remove_unused_layers no)
			(net "BMC_A_EXP_A_SPARE_0")
			(clearance 0.1651)
			(thermal_gap 0.1651)
		)
		(pad "C7" thru_hole circle
			(at 10.80008 3.599942 270)
			(size 0.762 0.762)
			(drill 0.359918)
			(layers "*.Cu" "*.Mask")
			(remove_unused_layers no)
			(net "PCIE_COMP_A_TO_SCC_A_RST_0")
			(clearance 0.1651)
			(thermal_gap 0.1651)
		)
		(pad "C8" thru_hole circle
			(at 12.599924 4.59994 270)
			(size 0.762 0.762)
			(drill 0.359918)
			(layers "*.Cu" "*.Mask")
			(remove_unused_layers no)
			(net "I2C_BMC_A_EXP_A_SCL")
			(clearance 0.1651)
			(thermal_gap 0.1651)
		)
		(pad "D1" thru_hole circle
			(at 0 4.99999 270)
			(size 0.762 0.762)
			(drill 0.359918)
			(layers "*.Cu" "*.Mask")
			(remove_unused_layers no)
			(net "PCIE_COMP_A_TO_SCC_A_CLK_0_DN")
			(clearance 0.1651)
			(thermal_gap 0.1651)
		)
		(pad "D2" thru_hole circle
			(at 1.800098 5.999988 270)
			(size 0.762 0.762)
			(drill 0.359918)
			(layers "*.Cu" "*.Mask")
			(remove_unused_layers no)
			(net "I2C_BMC_B_EXP_A_SDA")
			(clearance 0.1651)
			(thermal_gap 0.1651)
		)
		(pad "D3" thru_hole circle
			(at 3.599942 4.99999 270)
			(size 0.762 0.762)
			(drill 0.359918)
			(layers "*.Cu" "*.Mask")
			(remove_unused_layers no)
			(net "I2C_SCC_A_SDA_BUF")
			(clearance 0.1651)
			(thermal_gap 0.1651)
		)
		(pad "D4" thru_hole circle
			(at 5.40004 5.999988 270)
			(size 0.762 0.762)
			(drill 0.359918)
			(layers "*.Cu" "*.Mask")
			(remove_unused_layers no)
			(net "Net_52")
			(clearance 0.1651)
			(thermal_gap 0.1651)
		)
		(pad "D5" thru_hole circle
			(at 7.199884 4.99999 270)
			(size 0.762 0.762)
			(drill 0.359918)
			(layers "*.Cu" "*.Mask")
			(remove_unused_layers no)
			(net "UART_IOC_A_RX")
			(clearance 0.1651)
			(thermal_gap 0.1651)
		)
		(pad "D6" thru_hole circle
			(at 8.999982 5.999988 270)
			(size 0.762 0.762)
			(drill 0.359918)
			(layers "*.Cu" "*.Mask")
			(remove_unused_layers no)
			(net "BMC_A_EXP_A_SPARE_1")
			(clearance 0.1651)
			(thermal_gap 0.1651)
		)
		(pad "D7" thru_hole circle
			(at 10.80008 4.99999 270)
			(size 0.762 0.762)
			(drill 0.359918)
			(layers "*.Cu" "*.Mask")
			(remove_unused_layers no)
			(net "BMC_B_HEARTBEAT")
			(clearance 0.1651)
			(thermal_gap 0.1651)
		)
		(pad "D8" thru_hole circle
			(at 12.599924 5.999988 270)
			(size 0.762 0.762)
			(drill 0.359918)
			(layers "*.Cu" "*.Mask")
			(remove_unused_layers no)
			(net "I2C_BMC_A_EXP_A_SDA")
			(clearance 0.1651)
			(thermal_gap 0.1651)
		)
		(pad "E1" thru_hole circle
			(at 0 7.199884 270)
			(size 0.762 0.762)
			(drill 0.359918)
			(layers "*.Cu" "*.Mask")
			(remove_unused_layers no)
			(net "PCIE_SCC_A_TO_COMP_A_0_DP")
			(clearance 0.1651)
			(thermal_gap 0.1651)
		)
		(pad "E2" thru_hole circle
			(at 1.800098 8.199882 270)
			(size 0.762 0.762)
			(drill 0.359918)
			(layers "*.Cu" "*.Mask")
			(remove_unused_layers no)
			(net "PCIE_SCC_A_TO_COMP_A_1_DP")
			(clearance 0.1651)
			(thermal_gap 0.1651)
		)
		(pad "E3" thru_hole circle
			(at 3.599942 7.199884 270)
			(size 0.762 0.762)
			(drill 0.359918)
			(layers "*.Cu" "*.Mask")
			(remove_unused_layers no)
			(net "PCIE_SCC_A_TO_COMP_A_2_DP")
			(clearance 0.1651)
			(thermal_gap 0.1651)
		)
		(pad "E4" thru_hole circle
			(at 5.40004 8.199882 270)
			(size 0.762 0.762)
			(drill 0.359918)
			(layers "*.Cu" "*.Mask")
			(remove_unused_layers no)
			(net "PCIE_SCC_A_TO_COMP_A_3_DP")
			(clearance 0.1651)
			(thermal_gap 0.1651)
		)
		(pad "E5" thru_hole circle
			(at 7.199884 7.199884 270)
			(size 0.762 0.762)
			(drill 0.359918)
			(layers "*.Cu" "*.Mask")
			(remove_unused_layers no)
			(net "PCIE_SCC_A_TO_COMP_A_4_DP")
			(clearance 0.1651)
			(thermal_gap 0.1651)
		)
		(pad "E6" thru_hole circle
			(at 8.999982 8.199882 270)
			(size 0.762 0.762)
			(drill 0.359918)
			(layers "*.Cu" "*.Mask")
			(remove_unused_layers no)
			(net "PCIE_SCC_A_TO_COMP_A_5_DP")
			(clearance 0.1651)
			(thermal_gap 0.1651)
		)
		(pad "E7" thru_hole circle
			(at 10.80008 7.199884 270)
			(size 0.762 0.762)
			(drill 0.359918)
			(layers "*.Cu" "*.Mask")
			(remove_unused_layers no)
			(net "PCIE_SCC_A_TO_COMP_A_6_DP")
			(clearance 0.1651)
			(thermal_gap 0.1651)
		)
		(pad "E8" thru_hole circle
			(at 12.599924 8.199882 270)
			(size 0.762 0.762)
			(drill 0.359918)
			(layers "*.Cu" "*.Mask")
			(remove_unused_layers no)
			(net "PCIE_SCC_A_TO_COMP_A_7_DP")
			(clearance 0.1651)
			(thermal_gap 0.1651)
		)
		(pad "F1" thru_hole circle
			(at 0 8.599932 270)
			(size 0.762 0.762)
			(drill 0.359918)
			(layers "*.Cu" "*.Mask")
			(remove_unused_layers no)
			(net "PCIE_SCC_A_TO_COMP_A_0_DN")
			(clearance 0.1651)
			(thermal_gap 0.1651)
		)
		(pad "F2" thru_hole circle
			(at 1.800098 9.59993 270)
			(size 0.762 0.762)
			(drill 0.359918)
			(layers "*.Cu" "*.Mask")
			(remove_unused_layers no)
			(net "PCIE_SCC_A_TO_COMP_A_1_DN")
			(clearance 0.1651)
			(thermal_gap 0.1651)
		)
		(pad "F3" thru_hole circle
			(at 3.599942 8.599932 270)
			(size 0.762 0.762)
			(drill 0.359918)
			(layers "*.Cu" "*.Mask")
			(remove_unused_layers no)
			(net "PCIE_SCC_A_TO_COMP_A_2_DN")
			(clearance 0.1651)
			(thermal_gap 0.1651)
		)
		(pad "F4" thru_hole circle
			(at 5.40004 9.59993 270)
			(size 0.762 0.762)
			(drill 0.359918)
			(layers "*.Cu" "*.Mask")
			(remove_unused_layers no)
			(net "PCIE_SCC_A_TO_COMP_A_3_DN")
			(clearance 0.1651)
			(thermal_gap 0.1651)
		)
		(pad "F5" thru_hole circle
			(at 7.199884 8.599932 270)
			(size 0.762 0.762)
			(drill 0.359918)
			(layers "*.Cu" "*.Mask")
			(remove_unused_layers no)
			(net "PCIE_SCC_A_TO_COMP_A_4_DN")
			(clearance 0.1651)
			(thermal_gap 0.1651)
		)
		(pad "F6" thru_hole circle
			(at 8.999982 9.59993 270)
			(size 0.762 0.762)
			(drill 0.359918)
			(layers "*.Cu" "*.Mask")
			(remove_unused_layers no)
			(net "PCIE_SCC_A_TO_COMP_A_5_DN")
			(clearance 0.1651)
			(thermal_gap 0.1651)
		)
		(pad "F7" thru_hole circle
			(at 10.80008 8.599932 270)
			(size 0.762 0.762)
			(drill 0.359918)
			(layers "*.Cu" "*.Mask")
			(remove_unused_layers no)
			(net "PCIE_SCC_A_TO_COMP_A_6_DN")
			(clearance 0.1651)
			(thermal_gap 0.1651)
		)
		(pad "F8" thru_hole circle
			(at 12.599924 9.59993 270)
			(size 0.762 0.762)
			(drill 0.359918)
			(layers "*.Cu" "*.Mask")
			(remove_unused_layers no)
			(net "PCIE_SCC_A_TO_COMP_A_7_DN")
			(clearance 0.1651)
			(thermal_gap 0.1651)
		)
		(pad "GND1" thru_hole circle
			(at 0 2.500122 270)
			(size 0.762 0.762)
			(drill 0.359918)
			(layers "*.Cu" "*.Mask")
			(remove_unused_layers no)
			(net "GND")
			(clearance 0.1651)
			(thermal_gap 0.1651)
		)
		(pad "GND2" thru_hole circle
			(at 0 6.100064 270)
			(size 0.762 0.762)
			(drill 0.359918)
			(layers "*.Cu" "*.Mask")
			(remove_unused_layers no)
			(net "GND")
			(clearance 0.1651)
			(thermal_gap 0.1651)
		)
		(pad "GND3" thru_hole circle
			(at 0 9.700006 270)
			(size 0.762 0.762)
			(drill 0.359918)
			(layers "*.Cu" "*.Mask")
			(remove_unused_layers no)
			(net "GND")
			(clearance 0.1651)
			(thermal_gap 0.1651)
		)
		(pad "GND4" thru_hole circle
			(at 1.800098 -0.100076 270)
			(size 0.762 0.762)
			(drill 0.359918)
			(layers "*.Cu" "*.Mask")
			(remove_unused_layers no)
			(net "GND")
			(clearance 0.1651)
			(thermal_gap 0.1651)
		)
		(pad "GND5" thru_hole circle
			(at 1.800098 3.50012 270)
			(size 0.762 0.762)
			(drill 0.359918)
			(layers "*.Cu" "*.Mask")
			(remove_unused_layers no)
			(net "GND")
			(clearance 0.1651)
			(thermal_gap 0.1651)
		)
		(pad "GND6" thru_hole circle
			(at 1.800098 7.100062 270)
			(size 0.762 0.762)
			(drill 0.359918)
			(layers "*.Cu" "*.Mask")
			(remove_unused_layers no)
			(net "GND")
			(clearance 0.1651)
			(thermal_gap 0.1651)
		)
		(pad "GND7" thru_hole circle
			(at 1.800098 10.700004 270)
			(size 0.762 0.762)
			(drill 0.359918)
			(layers "*.Cu" "*.Mask")
			(remove_unused_layers no)
			(net "GND")
			(clearance 0.1651)
			(thermal_gap 0.1651)
		)
		(pad "GND8" thru_hole circle
			(at 3.599942 2.500122 270)
			(size 0.762 0.762)
			(drill 0.359918)
			(layers "*.Cu" "*.Mask")
			(remove_unused_layers no)
			(net "GND")
			(clearance 0.1651)
			(thermal_gap 0.1651)
		)
		(pad "GND9" thru_hole circle
			(at 3.599942 6.100064 270)
			(size 0.762 0.762)
			(drill 0.359918)
			(layers "*.Cu" "*.Mask")
			(remove_unused_layers no)
			(net "GND")
			(clearance 0.1651)
			(thermal_gap 0.1651)
		)
		(pad "GND10" thru_hole circle
			(at 3.599942 9.700006 270)
			(size 0.762 0.762)
			(drill 0.359918)
			(layers "*.Cu" "*.Mask")
			(remove_unused_layers no)
			(net "GND")
			(clearance 0.1651)
			(thermal_gap 0.1651)
		)
		(pad "GND11" thru_hole circle
			(at 5.40004 -0.100076 270)
			(size 0.762 0.762)
			(drill 0.359918)
			(layers "*.Cu" "*.Mask")
			(remove_unused_layers no)
			(net "GND")
			(clearance 0.1651)
			(thermal_gap 0.1651)
		)
		(pad "GND12" thru_hole circle
			(at 5.40004 3.50012 270)
			(size 0.762 0.762)
			(drill 0.359918)
			(layers "*.Cu" "*.Mask")
			(remove_unused_layers no)
			(net "GND")
			(clearance 0.1651)
			(thermal_gap 0.1651)
		)
		(pad "GND13" thru_hole circle
			(at 5.40004 7.100062 270)
			(size 0.762 0.762)
			(drill 0.359918)
			(layers "*.Cu" "*.Mask")
			(remove_unused_layers no)
			(net "GND")
			(clearance 0.1651)
			(thermal_gap 0.1651)
		)
		(pad "GND14" thru_hole circle
			(at 5.40004 10.700004 270)
			(size 0.762 0.762)
			(drill 0.359918)
			(layers "*.Cu" "*.Mask")
			(remove_unused_layers no)
			(net "GND")
			(clearance 0.1651)
			(thermal_gap 0.1651)
		)
		(pad "GND15" thru_hole circle
			(at 7.199884 2.500122 270)
			(size 0.762 0.762)
			(drill 0.359918)
			(layers "*.Cu" "*.Mask")
			(remove_unused_layers no)
			(net "GND")
			(clearance 0.1651)
			(thermal_gap 0.1651)
		)
		(pad "GND16" thru_hole circle
			(at 7.199884 6.100064 270)
			(size 0.762 0.762)
			(drill 0.359918)
			(layers "*.Cu" "*.Mask")
			(remove_unused_layers no)
			(net "GND")
			(clearance 0.1651)
			(thermal_gap 0.1651)
		)
		(pad "GND17" thru_hole circle
			(at 7.199884 9.700006 270)
			(size 0.762 0.762)
			(drill 0.359918)
			(layers "*.Cu" "*.Mask")
			(remove_unused_layers no)
			(net "GND")
			(clearance 0.1651)
			(thermal_gap 0.1651)
		)
		(pad "GND18" thru_hole circle
			(at 8.999982 -0.100076 270)
			(size 0.762 0.762)
			(drill 0.359918)
			(layers "*.Cu" "*.Mask")
			(remove_unused_layers no)
			(net "GND")
			(clearance 0.1651)
			(thermal_gap 0.1651)
		)
		(pad "GND19" thru_hole circle
			(at 8.999982 3.50012 270)
			(size 0.762 0.762)
			(drill 0.359918)
			(layers "*.Cu" "*.Mask")
			(remove_unused_layers no)
			(net "GND")
			(clearance 0.1651)
			(thermal_gap 0.1651)
		)
		(pad "GND20" thru_hole circle
			(at 8.999982 7.100062 270)
			(size 0.762 0.762)
			(drill 0.359918)
			(layers "*.Cu" "*.Mask")
			(remove_unused_layers no)
			(net "GND")
			(clearance 0.1651)
			(thermal_gap 0.1651)
		)
		(pad "GND21" thru_hole circle
			(at 8.999982 10.700004 270)
			(size 0.762 0.762)
			(drill 0.359918)
			(layers "*.Cu" "*.Mask")
			(remove_unused_layers no)
			(net "GND")
			(clearance 0.1651)
			(thermal_gap 0.1651)
		)
		(pad "GND22" thru_hole circle
			(at 10.80008 2.500122 270)
			(size 0.762 0.762)
			(drill 0.359918)
			(layers "*.Cu" "*.Mask")
			(remove_unused_layers no)
			(net "GND")
			(clearance 0.1651)
			(thermal_gap 0.1651)
		)
		(pad "GND23" thru_hole circle
			(at 10.80008 6.100064 270)
			(size 0.762 0.762)
			(drill 0.359918)
			(layers "*.Cu" "*.Mask")
			(remove_unused_layers no)
			(net "GND")
			(clearance 0.1651)
			(thermal_gap 0.1651)
		)
		(pad "GND24" thru_hole circle
			(at 10.80008 9.700006 270)
			(size 0.762 0.762)
			(drill 0.359918)
			(layers "*.Cu" "*.Mask")
			(remove_unused_layers no)
			(net "GND")
			(clearance 0.1651)
			(thermal_gap 0.1651)
		)
		(pad "GND25" thru_hole circle
			(at 12.599924 -0.100076 270)
			(size 0.762 0.762)
			(drill 0.359918)
			(layers "*.Cu" "*.Mask")
			(remove_unused_layers no)
			(net "GND")
			(clearance 0.1651)
			(thermal_gap 0.1651)
		)
	)
)
